# T6G (Grand Teton) — schematic netlist excerpt (pin names and nets, part order shuffled) for the footprints in the layout excerpt that follows; sources: Cadence DE-HDL packaged netlist, KiCad conversion of 04192023_DAF0TMB3IC0_F0TG_MB_C_brd_V02_OCP.brd

PC2146  Q_CAP  1UF 25V 10% X6S  pkg C0402  page 140 : A = GND ; B = P12V_OCP_REG_2
R23  Q_RES  33 5% CHIP  pkg 0402LF  page 80 : A = P3V3_OCP_SFF_EN ; B = P3V3_OCP_SFF_EN_R

(kicad_pcb
	(version 20260206)
	(generator "pcbnew")
	(generator_version "10.0")
	(general
		(thickness 1.6)
		(legacy_teardrops no)
	)
	(paper "A4")
	(title_block
		(title "04192023_DAF0TMB3IC0_F0TG_MB_C_brd_V02_OCP.brd")
		(comment 1 "Grand Teton / footprints 1543-1544 of 8354")
	)
	(layers
		(0 "F.Cu" signal "TOP")
		(4 "In1.Cu" signal "GND")
		(6 "In2.Cu" signal "IN1")
		(8 "In3.Cu" signal "GND1")
		(10 "In4.Cu" signal "IN2")
		(12 "In5.Cu" signal "GND2")
		(14 "In6.Cu" signal "IN3")
		(16 "In7.Cu" signal "GND3")
		(18 "In8.Cu" signal "VCC")
		(20 "In9.Cu" signal "VCC1")
		(22 "In10.Cu" signal "GND4")
		(24 "In11.Cu" signal "IN4")
		(26 "In12.Cu" signal "GND5")
		(28 "In13.Cu" signal "IN5")
		(30 "In14.Cu" signal "GND6")
		(32 "In15.Cu" signal "IN6")
		(34 "In16.Cu" signal "GND7")
		(2 "B.Cu" signal "BOTTOM")
		(9 "F.Adhes" user "F.Adhesive")
		(11 "B.Adhes" user "B.Adhesive")
		(13 "F.Paste" user "Package Geometry/Pastemask Top")
		(15 "B.Paste" user "Package Geometry/Pastemask Bottom")
		(5 "F.SilkS" user "Ref Des/Silkscreen Top")
		(7 "B.SilkS" user "Ref Des/Silkscreen Bottom")
		(1 "F.Mask" user "Board Geometry/Soldermask Top")
		(3 "B.Mask" user "Board Geometry/Soldermask Bottom")
		(17 "Dwgs.User" user "User.Drawings")
		(19 "Cmts.User" user "User.Comments")
		(21 "Eco1.User" user "User.Eco1")
		(23 "Eco2.User" user "User.Eco2")
		(25 "Edge.Cuts" user "Board Geometry/Outline")
		(27 "Margin" user)
		(31 "F.CrtYd" user "Package Geometry/Place Bound Top")
		(29 "B.CrtYd" user "Package Geometry/Place Bound Bottom")
		(35 "F.Fab" user "Ref Des/Assembly Top")
		(33 "B.Fab" user "Ref Des/Assembly Bottom")
	)
	(footprint ""
		(layer "F.Cu")
		(at 75.424538 -19.220942)
		(property "Reference" "PC2146"
			(at 0 0 0)
			(layer "F.SilkS")
			(hide yes)
			(effects
				(font
					(size 1.27 1.27)
				)
			)
		)
		(property "Value" ""
			(at 0 0 0)
			(layer "F.Fab")
			(effects
				(font
					(size 1.27 1.27)
				)
			)
		)
		(duplicate_pad_numbers_are_jumpers no)
		(fp_line
			(start -0.7874 -0.4064)
			(end 0.7874 -0.4064)
			(stroke
				(width 0.1524)
				(type default)
			)
			(layer "F.SilkS")
		)
		(fp_line
			(start -0.7874 0.4064)
			(end -0.7874 -0.4064)
			(stroke
				(width 0.1524)
				(type default)
			)
			(layer "F.SilkS")
		)
		(fp_line
			(start 0.7874 -0.4064)
			(end 0.7874 0.4064)
			(stroke
				(width 0.1524)
				(type default)
			)
			(layer "F.SilkS")
		)
		(fp_line
			(start 0.7874 0.4064)
			(end -0.7874 0.4064)
			(stroke
				(width 0.1524)
				(type default)
			)
			(layer "F.SilkS")
		)
		(fp_line
			(start -0.67945 -0.305054)
			(end -0.12065 -0.305054)
			(stroke
				(width 0.1)
				(type default)
			)
			(layer "F.Fab")
		)
		(fp_line
			(start -0.67945 0.3048)
			(end -0.67945 -0.305054)
			(stroke
				(width 0.1)
				(type default)
			)
			(layer "F.Fab")
		)
		(fp_line
			(start -0.12065 -0.305054)
			(end -0.12065 -0.2794)
			(stroke
				(width 0.1)
				(type default)
			)
			(layer "F.Fab")
		)
		(fp_line
			(start -0.12065 -0.2794)
			(end 0.12065 -0.2794)
			(stroke
				(width 0.1)
				(type default)
			)
			(layer "F.Fab")
		)
		(fp_line
			(start -0.12065 0.2794)
			(end -0.12065 0.3048)
			(stroke
				(width 0.1)
				(type default)
			)
			(layer "F.Fab")
		)
		(fp_line
			(start -0.12065 0.3048)
			(end -0.67945 0.3048)
			(stroke
				(width 0.1)
				(type default)
			)
			(layer "F.Fab")
		)
		(fp_line
			(start 0.120396 0.2794)
			(end -0.12065 0.2794)
			(stroke
				(width 0.1)
				(type default)
			)
			(layer "F.Fab")
		)
		(fp_line
			(start 0.120396 0.3048)
			(end 0.120396 0.2794)
			(stroke
				(width 0.1)
				(type default)
			)
			(layer "F.Fab")
		)
		(fp_line
			(start 0.12065 -0.3048)
			(end 0.67945 -0.3048)
			(stroke
				(width 0.1)
				(type default)
			)
			(layer "F.Fab")
		)
		(fp_line
			(start 0.12065 -0.2794)
			(end 0.12065 -0.3048)
			(stroke
				(width 0.1)
				(type default)
			)
			(layer "F.Fab")
		)
		(fp_line
			(start 0.67945 -0.3048)
			(end 0.67945 0.3048)
			(stroke
				(width 0.1)
				(type default)
			)
			(layer "F.Fab")
		)
		(fp_line
			(start 0.67945 0.3048)
			(end 0.120396 0.3048)
			(stroke
				(width 0.1)
				(type default)
			)
			(layer "F.Fab")
		)
		(pad "1" smd circle
			(at -0.40005 0)
			(size 0 0)
			(layers "F.Cu" "F.Mask" "F.Paste")
			(net "GND")
		)
		(pad "2" smd circle
			(at 0.40005 0)
			(size 0 0)
			(layers "F.Cu" "F.Mask" "F.Paste")
			(net "P12V_OCP_REG_2")
		)
	)
	(footprint ""
		(layer "F.Cu")
		(at 171.196 -112.359948 180)
		(property "Reference" "R23"
			(at 0 0 180)
			(layer "F.SilkS")
			(hide yes)
			(effects
				(font
					(size 1.27 1.27)
				)
			)
		)
		(property "Value" ""
			(at 0 0 180)
			(layer "F.Fab")
			(effects
				(font
					(size 1.27 1.27)
				)
			)
		)
		(duplicate_pad_numbers_are_jumpers no)
		(fp_line
			(start 0.7874 0.4064)
			(end -0.7874 0.4064)
			(stroke
				(width 0.1524)
				(type default)
			)
			(layer "F.SilkS")
		)
		(fp_line
			(start 0.7874 -0.4064)
			(end 0.7874 0.4064)
			(stroke
				(width 0.1524)
				(type default)
			)
			(layer "F.SilkS")
		)
		(fp_line
			(start -0.7874 0.4064)
			(end -0.7874 -0.4064)
			(stroke
				(width 0.1524)
				(type default)
			)
			(layer "F.SilkS")
		)
		(fp_line
			(start -0.7874 -0.4064)
			(end 0.7874 -0.4064)
			(stroke
				(width 0.1524)
				(type default)
			)
			(layer "F.SilkS")
		)
		(fp_line
			(start 0.67945 0.3048)
			(end 0.120396 0.3048)
			(stroke
				(width 0.1)
				(type default)
			)
			(layer "F.Fab")
		)
		(fp_line
			(start 0.67945 -0.3048)
			(end 0.67945 0.3048)
			(stroke
				(width 0.1)
				(type default)
			)
			(layer "F.Fab")
		)
		(fp_line
			(start 0.12065 -0.2794)
			(end 0.12065 -0.3048)
			(stroke
				(width 0.1)
				(type default)
			)
			(layer "F.Fab")
		)
		(fp_line
			(start 0.12065 -0.3048)
			(end 0.67945 -0.3048)
			(stroke
				(width 0.1)
				(type default)
			)
			(layer "F.Fab")
		)
		(fp_line
			(start 0.120396 0.3048)
			(end 0.120396 0.2794)
			(stroke
				(width 0.1)
				(type default)
			)
			(layer "F.Fab")
		)
		(fp_line
			(start 0.120396 0.2794)
			(end -0.12065 0.2794)
			(stroke
				(width 0.1)
				(type default)
			)
			(layer "F.Fab")
		)
		(fp_line
			(start -0.12065 0.3048)
			(end -0.67945 0.3048)
			(stroke
				(width 0.1)
				(type default)
			)
			(layer "F.Fab")
		)
		(fp_line
			(start -0.12065 0.2794)
			(end -0.12065 0.3048)
			(stroke
				(width 0.1)
				(type default)
			)
			(layer "F.Fab")
		)
		(fp_line
			(start -0.12065 -0.2794)
			(end 0.12065 -0.2794)
			(stroke
				(width 0.1)
				(type default)
			)
			(layer "F.Fab")
		)
		(fp_line
			(start -0.12065 -0.305054)
			(end -0.12065 -0.2794)
			(stroke
				(width 0.1)
				(type default)
			)
			(layer "F.Fab")
		)
		(fp_line
			(start -0.67945 0.3048)
			(end -0.67945 -0.305054)
			(stroke
				(width 0.1)
				(type default)
			)
			(layer "F.Fab")
		)
		(fp_line
			(start -0.67945 -0.305054)
			(end -0.12065 -0.305054)
			(stroke
				(width 0.1)
				(type default)
			)
			(layer "F.Fab")
		)
		(pad "1" smd circle
			(at -0.40005 0 180)
			(size 0 0)
			(layers "F.Cu" "F.Mask" "F.Paste")
			(net "P3V3_OCP_SFF_EN")
		)
		(pad "2" smd circle
			(at 0.40005 0 180)
			(size 0 0)
			(layers "F.Cu" "F.Mask" "F.Paste")
			(net "P3V3_OCP_SFF_EN_R")
		)
	)
)
